# BASEBOARD_FAB2 (Tioga Pass) — schematic netlist excerpt (pin names and nets, part order shuffled) for the footprints in the layout excerpt that follows; sources: Cadence DE-HDL packaged netlist, KiCad conversion of Wiwynn_Tioga_Pass_MB.brd

C6A3  CAP  10UF 4V 20% X6S  pkg 0603LF  page 232 : A = PVPP_DEF ; B = GND

U6W11  PCA9554PWR-GP  pkg DISCRET-G1  page 164
  A0  = PCA9554_A0
  A1  = PCA9554_A1
  A2  = PCA9554_A2
  P0  = FM_MB_SLOT_ID0
  P1  = FM_MB_SLOT_ID1
  P2  = FM_MB_SLOT_ID2
  P3  = FM_CPU_BMC_INIT
  GND  = GND
  P4  = NC
  P5  = NC
  P6  = NC
  P7  = NC
  \int#\  = PCA9554_INT_N
  SCL  = SMB_SENSOR_STBY_LVC3_SCL
  SDA  = SMB_SENSOR_STBY_LVC3_SDA
  VCC  = P3V3_STBY

(kicad_pcb
	(version 20260206)
	(generator "pcbnew")
	(generator_version "10.0")
	(general
		(thickness 1.6)
		(legacy_teardrops no)
	)
	(paper "A4")
	(title_block
		(title "Wiwynn_Tioga_Pass_MB.brd")
		(comment 1 "Tioga Pass / footprints 2157-2158 of 4770")
	)
	(layers
		(0 "F.Cu" signal "TOP")
		(4 "In1.Cu" signal "L2GND")
		(6 "In2.Cu" signal "L3")
		(8 "In3.Cu" signal "L4GND")
		(10 "In4.Cu" signal "L5")
		(12 "In5.Cu" signal "L6GND")
		(14 "In6.Cu" signal "L7VCC")
		(16 "In7.Cu" signal "L8VCC")
		(18 "In8.Cu" signal "L9GND")
		(20 "In9.Cu" signal "L10")
		(22 "In10.Cu" signal "L11GND")
		(24 "In11.Cu" signal "L12")
		(26 "In12.Cu" signal "L13GND")
		(2 "B.Cu" signal "BOTTOM")
		(9 "F.Adhes" user "F.Adhesive")
		(11 "B.Adhes" user "B.Adhesive")
		(13 "F.Paste" user "Package Geometry/Pastemask Top")
		(15 "B.Paste" user "Package Geometry/Pastemask Bottom")
		(5 "F.SilkS" user "Ref Des/Silkscreen Top")
		(7 "B.SilkS" user "Ref Des/Silkscreen Bottom")
		(1 "F.Mask" user "Board Geometry/Soldermask Top")
		(3 "B.Mask" user "Board Geometry/Soldermask Bottom")
		(17 "Dwgs.User" user "User.Drawings")
		(19 "Cmts.User" user "User.Comments")
		(21 "Eco1.User" user "User.Eco1")
		(23 "Eco2.User" user "User.Eco2")
		(25 "Edge.Cuts" user "Board Geometry/Outline")
		(27 "Margin" user)
		(31 "F.CrtYd" user "Package Geometry/Place Bound Top")
		(29 "B.CrtYd" user "Package Geometry/Place Bound Bottom")
		(35 "F.Fab" user "Ref Des/Assembly Top")
		(33 "B.Fab" user "Ref Des/Assembly Bottom")
	)
	(footprint ""
		(layer "F.Cu")
		(at 429.54448 -14.605 180)
		(property "Reference" "U6W11"
			(at 0 0 180)
			(layer "F.SilkS")
			(hide yes)
			(effects
				(font
					(size 1.27 1.27)
				)
			)
		)
		(property "Value" "*"
			(at 0.127 -12.51585 180)
			(unlocked yes)
			(layer "F.Fab")
			(hide yes)
			(effects
				(font
					(size 0.889 0.889)
					(thickness 0.1524)
				)
			)
		)
		(property "Device Type" "PCA9554PWR-GP_DISCRET-G1-PCA95A"
			(at 0.1016 -14.52245 180)
			(unlocked yes)
			(layer "F.Fab")
			(hide yes)
			(effects
				(font
					(size 0.889 0.889)
					(thickness 0.1524)
				)
			)
		)
		(duplicate_pad_numbers_are_jumpers no)
		(fp_line
			(start 2.3622 1.778)
			(end -2.921 1.778)
			(stroke
				(width 0.1524)
				(type default)
			)
			(layer "F.SilkS")
		)
		(fp_line
			(start 2.3622 -1.778)
			(end 2.3622 1.778)
			(stroke
				(width 0.1524)
				(type default)
			)
			(layer "F.SilkS")
		)
		(fp_line
			(start -2.54 0)
			(end -3.0988 0.5588)
			(stroke
				(width 0.1524)
				(type default)
			)
			(layer "F.SilkS")
		)
		(fp_line
			(start -2.54 0)
			(end -3.0988 -0.5588)
			(stroke
				(width 0.1524)
				(type default)
			)
			(layer "F.SilkS")
		)
		(fp_line
			(start -2.921 3.81)
			(end -2.921 1.778)
			(stroke
				(width 0.508)
				(type default)
			)
			(layer "F.SilkS")
		)
		(fp_line
			(start -3.0988 -1.778)
			(end 2.3622 -1.778)
			(stroke
				(width 0.1524)
				(type default)
			)
			(layer "F.SilkS")
		)
		(fp_line
			(start -3.0988 -1.778)
			(end -3.0988 1.778)
			(stroke
				(width 0.1524)
				(type default)
			)
			(layer "F.SilkS")
		)
		(fp_poly
			(pts
				(xy -2.4638 -1.778) (xy -2.4638 1.778) (xy 2.3622 1.778) (xy 2.3622 -1.778)
			)
			(stroke
				(width 0)
				(type default)
			)
			(fill yes)
			(layer "F.SilkS")
		)
		(fp_rect
			(start -3.175 4.064)
			(end 3.175 -4.064)
			(stroke
				(width 0)
				(type default)
			)
			(fill no)
			(layer "F.CrtYd")
		)
		(fp_poly
			(pts
				(xy -3.175 -4.064) (xy 3.175 -4.064) (xy 3.175 4.064) (xy -3.175 4.064)
			)
			(stroke
				(width 0)
				(type default)
			)
			(fill no)
			(layer "F.Fab")
		)
		(pad "1" smd rect
			(at -2.27584 2.8194 180)
			(size 0.3556 1.524)
			(layers "F.Cu" "F.Mask" "F.Paste")
			(net "PCA9554_A0")
		)
		(pad "2" smd rect
			(at -1.6256 2.8194 180)
			(size 0.3556 1.524)
			(layers "F.Cu" "F.Mask" "F.Paste")
			(net "PCA9554_A1")
		)
		(pad "3" smd rect
			(at -0.97536 2.8194 180)
			(size 0.3556 1.524)
			(layers "F.Cu" "F.Mask" "F.Paste")
			(net "PCA9554_A2")
		)
		(pad "4" smd rect
			(at -0.32512 2.8194 180)
			(size 0.3556 1.524)
			(layers "F.Cu" "F.Mask" "F.Paste")
			(net "FM_MB_SLOT_ID0")
		)
		(pad "5" smd rect
			(at 0.32512 2.8194 180)
			(size 0.3556 1.524)
			(layers "F.Cu" "F.Mask" "F.Paste")
			(net "FM_MB_SLOT_ID1")
		)
		(pad "6" smd rect
			(at 0.97536 2.8194 180)
			(size 0.3556 1.524)
			(layers "F.Cu" "F.Mask" "F.Paste")
			(net "FM_MB_SLOT_ID2")
		)
		(pad "7" smd rect
			(at 1.6256 2.8194 180)
			(size 0.3556 1.524)
			(layers "F.Cu" "F.Mask" "F.Paste")
			(net "FM_CPU_BMC_INIT")
		)
		(pad "8" smd rect
			(at 2.27584 2.8194 180)
			(size 0.3556 1.524)
			(layers "F.Cu" "F.Mask" "F.Paste")
			(net "GND")
		)
		(pad "9" smd rect
			(at 2.27584 -2.8194 180)
			(size 0.3556 1.524)
			(layers "F.Cu" "F.Mask" "F.Paste")
			(net "Net_6513")
		)
		(pad "10" smd rect
			(at 1.6256 -2.8194 180)
			(size 0.3556 1.524)
			(layers "F.Cu" "F.Mask" "F.Paste")
			(net "Net_6512")
		)
		(pad "11" smd rect
			(at 0.97536 -2.8194 180)
			(size 0.3556 1.524)
			(layers "F.Cu" "F.Mask" "F.Paste")
			(net "Net_6511")
		)
		(pad "12" smd rect
			(at 0.32512 -2.8194 180)
			(size 0.3556 1.524)
			(layers "F.Cu" "F.Mask" "F.Paste")
			(net "Net_6510")
		)
		(pad "13" smd rect
			(at -0.32512 -2.8194 180)
			(size 0.3556 1.524)
			(layers "F.Cu" "F.Mask" "F.Paste")
			(net "PCA9554_INT_N")
		)
		(pad "14" smd rect
			(at -0.97536 -2.8194 180)
			(size 0.3556 1.524)
			(layers "F.Cu" "F.Mask" "F.Paste")
			(net "SMB_SENSOR_STBY_LVC3_SCL")
		)
		(pad "15" smd rect
			(at -1.6256 -2.8194 180)
			(size 0.3556 1.524)
			(layers "F.Cu" "F.Mask" "F.Paste")
			(net "SMB_SENSOR_STBY_LVC3_SDA")
		)
		(pad "16" smd rect
			(at -2.27584 -2.8194 180)
			(size 0.3556 1.524)
			(layers "F.Cu" "F.Mask" "F.Paste")
			(net "P3V3_STBY")
		)
	)
	(footprint ""
		(layer "F.Cu")
		(at 320.194432 -149.86 90)
		(property "Reference" "C6A3"
			(at 0 0 90)
			(layer "F.SilkS")
			(hide yes)
			(effects
				(font
					(size 1.27 1.27)
				)
			)
		)
		(property "Value" ""
			(at 0 0 90)
			(layer "F.Fab")
			(effects
				(font
					(size 1.27 1.27)
				)
			)
		)
		(duplicate_pad_numbers_are_jumpers no)
		(fp_poly
			(pts
				(xy -0.4953 -0.2032) (xy 0.4953 -0.2032) (xy 0.4953 1.6002) (xy -0.4953 1.6002)
			)
			(stroke
				(width 0)
				(type default)
			)
			(fill no)
			(layer "F.CrtYd")
		)
		(fp_line
			(start 0.4953 -0.2032)
			(end 0.4953 1.6002)
			(stroke
				(width 0.1)
				(type default)
			)
			(layer "F.Fab")
		)
		(fp_line
			(start -0.4953 -0.2032)
			(end 0.4953 -0.2032)
			(stroke
				(width 0.1)
				(type default)
			)
			(layer "F.Fab")
		)
		(fp_line
			(start 0.4953 1.6002)
			(end -0.4953 1.6002)
			(stroke
				(width 0.1)
				(type default)
			)
			(layer "F.Fab")
		)
		(fp_line
			(start -0.4953 1.6002)
			(end -0.4953 -0.2032)
			(stroke
				(width 0.1)
				(type default)
			)
			(layer "F.Fab")
		)
		(pad "1" smd rect
			(at 0 0 90)
			(size 0.762 0.889)
			(layers "F.Cu" "F.Mask" "F.Paste")
			(net "PVPP_DEF")
		)
		(pad "2" smd rect
			(at 0 1.397 90)
			(size 0.762 0.889)
			(layers "F.Cu" "F.Mask" "F.Paste")
			(net "GND")
		)
		(zone
			(layer "F.Cu")
			(hatch none 0.5)
			(connect_pads
				(clearance 0)
			)
			(min_thickness 0.25)
			(keepout
				(tracks not_allowed)
				(vias allowed)
				(pads allowed)
				(copperpour not_allowed)
				(footprints allowed)
			)
			(placement
				(enabled no)
				(sheetname "")
			)
			(fill
				(thermal_gap 0.5)
				(thermal_bridge_width 0.5)
				(island_removal_mode 0)
			)
			(polygon
				(pts
					(xy 320.638932 -149.479) (xy 320.638932 -150.241) (xy 321.146932 -150.241) (xy 321.146932 -149.479)
				)
			)
		)
	)
)
